FILE_TYPE = CONNECTIVITY;
{Allegro Design Entry HDL 16.6-p007 (v16-6-112F) 10/10/2012}
"PAGE_NUMBER" = 73;
0"NC";
1"PVCCMCP_CPU1\g";
2"PVCCMCP_CPU1\g";
3"PVCCMCP_CPU1\g";
4"PVCCIO_CPU1\g";
5"TP_CPU1_RSVD_61";
6"TP_CPU1_KTI2_DFX_DN";
7"TP_CPU1_RSVD_64";
8"TP_CPU1_RSVD_66";
9"TP_CPU1_RSVD_67";
10"TP_CPU1_RSVD_69";
11"TP_CPU1_RSVD_70";
12"TP_CPU1_RSVD_72";
13"TP_CPU1_RSVD_73";
14"PD_CPU1_MCP01_DMON";
15"VSENSE_PVCCIO_CPU1_SKT_VRTN";
16"TP_CPU1_KTI2_AMONV";
17"VSENSE_PVSA_CPU1_SKT_VSEN";
18"VSENSE_PVSA_CPU1_SKT_VRTN";
19"VSENSE_PVCCMCP_CPU1_SKT_VSEN";
20"VSENSE_PVCCMCP_CPU1_SKT_VRTN";
21"VSENSE_PVCCIOMCP_CPU1_SKT_VSEN";
22"VSENSE_PVCCIOMCP_CPU1_SKT_VRTN";
23"VSENSE_PVCCIO_CPU1_SKT_VSEN";
24"TP_CPU1_RSVD_0";
25"TP_CPU1_RSVD_1";
26"TP_CPU1_RSVD_2";
27"TP_CPU1_RSVD_3";
28"TP_CPU1_RSVD_4";
29"TP_CPU1_RSVD_5";
30"TP_CPU1_RSVD_6";
31"TP_CPU1_RSVD_7";
32"TP_CPU1_RSVD_8";
33"TP_CPU1_RSVD_9";
34"TP_CPU1_RSVD_10";
35"TP_CPU1_RSVD_11";
36"TP_CPU1_RSVD_12";
37"TP_CPU1_RSVD_13";
38"TP_CPU1_RSVD_14";
39"TP_CPU1_RSVD_15";
40"TP_CPU1_RSVD_16";
41"TP_CPU1_RSVD_17";
42"TP_CPU1_RSVD_18";
43"TP_CPU1_RSVD_19";
44"TP_CPU1_RSVD_20";
45"TP_CPU1_RSVD_21";
46"TP_CPU1_RSVD_22";
47"TP_CPU1_RSVD_23";
48"TP_CPU1_RSVD_24";
49"TP_CPU1_RSVD_25";
50"TP_CPU1_RSVD_26";
51"TP_CPU1_RSVD_27";
52"TP_CPU1_RSVD_28";
53"TP_CPU1_RSVD_29";
54"TP_CPU1_RSVD_30";
55"TP_CPU1_RSVD_31";
56"TP_CPU1_RSVD_32";
57"TP_CPU1_RSVD_33";
58"TP_CPU1_RSVD_34";
59"TP_CPU1_RSVD_35";
60"TP_CPU1_RSVD_36";
61"TP_CPU1_RSVD_37";
62"TP_CPU1_RSVD_38";
63"TP_CPU1_RSVD_39";
64"TP_CPU1_RSVD_40";
65"TP_CPU1_RSVD_41";
66"TP_CPU1_RSVD_42";
67"TP_CPU1_RSVD_43";
68"TP_CPU1_RSVD_44";
69"TP_CPU1_RSVD_45";
70"TP_CPU1_RSVD_46";
71"TP_CPU1_RSVD_47";
72"TP_CPU1_RSVD_48";
73"TP_CPU1_RSVD_49";
74"TP_CPU1_RSVD_50";
75"TP_CPU1_RSVD_51";
76"TP_CPU1_RSVD_53";
77"TP_CPU1_RSVD_54";
78"TP_CPU1_RSVD_55";
79"TP_CPU1_RSVD_56";
80"TP_CPU1_RSVD_57";
81"TP_CPU1_RSVD_59";
82"TP_CPU1_RSVD_60";
%"VCC_CORE"
"1","(-1800,4100)","0","mstr_symbols","I104";
;
CDS_LIB"mstr_symbols"
HDL_POWER"PVCCMCP_CPU1";
"A"1;
%"VCC_CORE"
"1","(-6600,1975)","0","mstr_symbols","I105";
;
CDS_LIB"mstr_symbols"
HDL_POWER"PVCCMCP_CPU1";
"A"2;
%"SKX_EXT_B"
"22","(-4000,2550)","0","chpset_lib","I107";
;
CDS_SEC"22"
CDS_LOCATION"U2D1"
SEC"22"
CDS_LIB"chpset_lib"
SEC_TYPE"BGA1"
PACK_TYPE"BGA1"
MATERIAL"IC"
PART_NUMBER"TBD"
LOCATION"U2D1";
"VSS_VCCSA_SENSE"
$PN"CG76"18;
"VSS_VCCIO_SENSE"
$PN"BF5"15;
"VCCSA_SENSE"
$PN"CE76"17;
"VCCIO_SENSE"
$PN"BH5"23;
"VCCIO<0>"
$PN"EE10"4;
"VCCIO<1>"
$PN"AE10"4;
"VCCIO<2>"
$PN"AF5"4;
"VCCIO<3>"
$PN"DV11"4;
"VCCIO<4>"
$PN"AM5"4;
"VCCIO<5>"
$PN"AT5"4;
"VCCIO<6>"
$PN"AT7"4;
"VCCIO<7>"
$PN"BE24"4;
"VCCIO<8>"
$PN"DK21"4;
"VCCIO<9>"
$PN"CF5"4;
"VCCIO<10>"
$PN"CG14"4;
"VCCIO<11>"
$PN"CL20"4;
"VCCIO<12>"
$PN"CP13"4;
"VCCIO<13>"
$PN"DE14"4;
"VCCIO<14>"
$PN"DC18"4;
"VCCIO<15>"
$PN"CY17"4;
"VCCIO<16>"
$PN"CU18"4;
"VCCIO<17>"
$PN"CV21"4;
"VCCIO<18>"
$PN"CU12"4;
"VCCIO<19>"
$PN"CN6"4;
"RSVD<0>"
$PN"EF83"24;
"RSVD<1>"
$PN"EF81"25;
"RSVD<2>"
$PN"EF77"26;
"RSVD<3>"
$PN"EF47"27;
"RSVD<4>"
$PN"EE84"28;
"RSVD<5>"
$PN"EE82"29;
"RSVD<6>"
$PN"EE6"30;
"RSVD<7>"
$PN"EE46"31;
"RSVD<8>"
$PN"EE16"32;
"RSVD<9>"
$PN"ED83"33;
"RSVD<10>"
$PN"ED5"34;
"RSVD<11>"
$PN"ED45"35;
"RSVD<12>"
$PN"EC84"36;
"RSVD<13>"
$PN"EC44"37;
"RSVD<14>"
$PN"EC4"38;
"RSVD<15>"
$PN"EC16"39;
"RSVD<16>"
$PN"EB85"40;
"RSVD<17>"
$PN"EB5"41;
"RSVD<18>"
$PN"EB3"42;
"RSVD<19>"
$PN"EA44"43;
"RSVD<20>"
$PN"EA4"44;
"RSVD<21>"
$PN"DY3"45;
"RSVD<22>"
$PN"DW46"46;
"RSVD<23>"
$PN"DW44"47;
"RSVD<24>"
$PN"DV71"48;
"RSVD<25>"
$PN"DV61"49;
"RSVD<26>"
$PN"DU44"50;
"RSVD<27>"
$PN"DT71"51;
"RSVD<28>"
$PN"DR44"52;
"RSVD<29>"
$PN"DP65"53;
"RSVD<30>"
$PN"DP17"54;
"RSVD<31>"
$PN"DN66"55;
"RSVD<32>"
$PN"DN62"56;
"RSVD<33>"
$PN"DM67"57;
"RSVD<34>"
$PN"DL66"58;
"RSVD<35>"
$PN"DL38"59;
"RSVD<36>"
$PN"DK67"60;
"RSVD<37>"
$PN"DK65"61;
"RSVD<38>"
$PN"DK37"62;
"RSVD<39>"
$PN"DK15"63;
"RSVD<40>"
$PN"DJ66"64;
"RSVD<41>"
$PN"DJ36"65;
"RSVD<42>"
$PN"DH65"66;
"RSVD<43>"
$PN"DG64"67;
"RSVD<44>"
$PN"DG36"68;
"RSVD<45>"
$PN"DD51"69;
"RSVD<46>"
$PN"DC52"70;
"RSVD<47>"
$PN"DC46"71;
"RSVD<48>"
$PN"DA56"72;
"RSVD<49>"
$PN"DA54"73;
"RSVD<50>"
$PN"DA52"74;
"RSVD<51>"
$PN"DA40"75;
"RSVD<52>"
$PN"DA24"1;
"RSVD<53>"
$PN"CY73"76;
"RSVD<54>"
$PN"CY63"77;
"RSVD<55>"
$PN"CY57"78;
"RSVD<56>"
$PN"CY53"79;
"RSVD<57>"
$PN"CY39"80;
"RSVD<58>"
$PN"CY25"1;
"RSVD<59>"
$PN"CY23"81;
"RSVD<60>"
$PN"CW62"82;
"RSVD<61>"
$PN"CW60"5;
"RSVD<62>"
$PN"CW24"2;
"RSVD<63>"
$PN"CW22"6;
"RSVD<64>"
$PN"CV69"7;
"RSVD<65>"
$PN"CV23"2;
"RSVD<66>"
$PN"CU60"8;
"RSVD<67>"
$PN"CU6"9;
"RSVD<68>"
$PN"CU24"2;
"RSVD<69>"
$PN"CT69"10;
"RSVD<70>"
$PN"CT5"11;
"RSVD<71>"
$PN"CT23"2;
"RSVD<72>"
$PN"CR60"12;
"RSVD<73>"
$PN"CP31"13;
"RSVD<74>"
$PN"CP23"2;
"RSVD<75>"
$PN"CN28"14;
"RSVD<76>"
$PN"CN24"3;
"RSVD<77>"
$PN"CN22"16;
"RSVD<78>"
$PN"CM25"3;
"RSVD<79>"
$PN"CM23"3;
"RSVD<80>"
$PN"CL26"3;
"CD_VSS_VCC_CORE_SENSE"
$PN"BL16"20;
"CD_VCC_CORE_SENSE"
$PN"BN16"19;
"CD_VCCP_SENSE<0>"
$PN"BU16"22;
"CD_VCCP_SENSE<1>"
$PN"BT17"21;
%"VCC_CORE"
"1","(-5925,2950)","0","mstr_symbols","I108";
;
CDS_LIB"mstr_symbols"
HDL_POWER"PVCCMCP_CPU1";
"A"3;
%"PVCCIO_CPU1"
"1","(-5350,4425)","0","mstr_symbols","I22";
;
HDL_POWER"PVCCIO_CPU1"
BODY_TYPE"PLUMBING"
CDS_LIB"mstr_symbols"
VOLTAGE"1.1V";
"G\NAC"4;
END.
